(kicad_pcb
	(version 20241229)
	(generator "pcbnew")
	(generator_version "9.0")
	(general
		(thickness 1.294)
		(legacy_teardrops no)
	)
	(paper "A3")
	(title_block
		(title "Kintex 410T devboard")
		(date "2024-04-03")
		(rev "1.1.2")
		(comment 9 "footprint 289 of 975 (U20), pads 1-73 of 73")
	)
	(layers
		(0 "F.Cu" mixed)
		(4 "In1.Cu" power)
		(6 "In2.Cu" power)
		(8 "In3.Cu" mixed)
		(10 "In4.Cu" power)
		(12 "In5.Cu" mixed)
		(14 "In6.Cu" power)
		(16 "In7.Cu" mixed)
		(18 "In8.Cu" power)
		(2 "B.Cu" mixed)
		(9 "F.Adhes" user "F.Adhesive")
		(11 "B.Adhes" user "B.Adhesive")
		(13 "F.Paste" user)
		(15 "B.Paste" user)
		(5 "F.SilkS" user "F.Silkscreen")
		(7 "B.SilkS" user "B.Silkscreen")
		(1 "F.Mask" user)
		(3 "B.Mask" user)
		(17 "Dwgs.User" user "User.Drawings")
		(19 "Cmts.User" user "User.Comments")
		(21 "Eco1.User" user "User.Eco1")
		(23 "Eco2.User" user "User.Eco2")
		(25 "Edge.Cuts" user)
		(27 "Margin" user)
		(31 "F.CrtYd" user "F.Courtyard")
		(29 "B.CrtYd" user "B.Courtyard")
		(35 "F.Fab" user)
		(33 "B.Fab" user)
	)
	(footprint "antmicro-footprints:QFN-56-1EP_8x8mm_P0.5mm"
		(layer "F.Cu")
		(at 248.4 135.9 180)
		(descr "QFN 56 Pin")
		(tags "QFN")
		(property "Reference" "U20"
			(at 1.82 4.7 180)
			(layer "F.SilkS")
			(effects
				(font
					(size 0.7 0.7)
					(thickness 0.15)
				)
				(justify left bottom)
			)
		)
		(property "Value" "FT4232H_VQFN"
			(at 0 5.32 180)
			(layer "F.Fab")
			(effects
				(font
					(size 0.7 0.7)
					(thickness 0.15)
				)
				(justify left bottom)
			)
		)
		(property "Description" "Interface Bridges, USB to UART, MPSSE, 1.62 V, 1.98 V, VQFN, 56 Pins, -40 °C"
			(at 0 0 180)
			(layer "F.Fab")
			(hide yes)
			(effects
				(font
					(size 1.27 1.27)
					(thickness 0.15)
				)
			)
		)
		(property "Author" "Antmicro"
			(at 496.8 271.8 0)
			(layer "F.Fab")
			(hide yes)
			(effects
				(font
					(size 1 1)
					(thickness 0.15)
				)
			)
		)
		(property "License" "Apache-2.0"
			(at 496.8 271.8 0)
			(layer "F.Fab")
			(hide yes)
			(effects
				(font
					(size 1 1)
					(thickness 0.15)
				)
			)
		)
		(property "MPN" "FT4232H-56Q-REEL"
			(at 496.8 271.8 0)
			(layer "F.Fab")
			(hide yes)
			(effects
				(font
					(size 1 1)
					(thickness 0.15)
				)
			)
		)
		(property "Manufacturer" "FTDI Chip"
			(at 496.8 271.8 0)
			(layer "F.Fab")
			(hide yes)
			(effects
				(font
					(size 1 1)
					(thickness 0.15)
				)
			)
		)
		(sheetname "USB PHY")
		(sheetfile "usb-phy.kicad_sch")
		(attr smd)
		(pad "" smd roundrect
			(at -2.101 -2.101 180)
			(size 1.13 1.13)
			(layers "F.Paste")
			(roundrect_rratio 0.221239)
		)
		(pad "" smd roundrect
			(at -2.101 -0.7 180)
			(size 1.13 1.13)
			(layers "F.Paste")
			(roundrect_rratio 0.221239)
		)
		(pad "" smd roundrect
			(at -2.101 0.699 180)
			(size 1.13 1.13)
			(layers "F.Paste")
			(roundrect_rratio 0.221239)
		)
		(pad "" smd roundrect
			(at -2.101 2.1 180)
			(size 1.13 1.13)
			(layers "F.Paste")
			(roundrect_rratio 0.221239)
		)
		(pad "" smd roundrect
			(at -0.7 -2.101 180)
			(size 1.13 1.13)
			(layers "F.Paste")
			(roundrect_rratio 0.221239)
		)
		(pad "" smd roundrect
			(at -0.7 -0.7 180)
			(size 1.13 1.13)
			(layers "F.Paste")
			(roundrect_rratio 0.221239)
		)
		(pad "" smd roundrect
			(at -0.7 0.699 180)
			(size 1.13 1.13)
			(layers "F.Paste")
			(roundrect_rratio 0.221239)
		)
		(pad "" smd roundrect
			(at -0.7 2.1 180)
			(size 1.13 1.13)
			(layers "F.Paste")
			(roundrect_rratio 0.221239)
		)
		(pad "" smd roundrect
			(at 0.699 -2.101 180)
			(size 1.13 1.13)
			(layers "F.Paste")
			(roundrect_rratio 0.221239)
		)
		(pad "" smd roundrect
			(at 0.699 -0.7 180)
			(size 1.13 1.13)
			(layers "F.Paste")
			(roundrect_rratio 0.221239)
		)
		(pad "" smd roundrect
			(at 0.699 0.699 180)
			(size 1.13 1.13)
			(layers "F.Paste")
			(roundrect_rratio 0.221239)
		)
		(pad "" smd roundrect
			(at 0.699 2.1 180)
			(size 1.13 1.13)
			(layers "F.Paste")
			(roundrect_rratio 0.221239)
		)
		(pad "" smd roundrect
			(at 2.1 -2.101 180)
			(size 1.13 1.13)
			(layers "F.Paste")
			(roundrect_rratio 0.221239)
		)
		(pad "" smd roundrect
			(at 2.1 -0.7 180)
			(size 1.13 1.13)
			(layers "F.Paste")
			(roundrect_rratio 0.221239)
		)
		(pad "" smd roundrect
			(at 2.1 0.699 180)
			(size 1.13 1.13)
			(layers "F.Paste")
			(roundrect_rratio 0.221239)
		)
		(pad "" smd roundrect
			(at 2.1 2.1 180)
			(size 1.13 1.13)
			(layers "F.Paste")
			(roundrect_rratio 0.221239)
		)
		(pad "1" smd roundrect
			(at -3.938 -3.25 180)
			(size 0.875 0.3)
			(layers "F.Cu" "F.Mask" "F.Paste")
			(roundrect_rratio 0.25)
			(net 997 "/USB PHY/FTDI_EECS")
			(pinfunction "EECS")
			(pintype "bidirectional")
		)
		(pad "2" smd roundrect
			(at -3.938 -2.75 180)
			(size 0.875 0.3)
			(layers "F.Cu" "F.Mask" "F.Paste")
			(roundrect_rratio 0.25)
			(net 712 "/USB PHY/FTDI_VCORE")
			(pinfunction "V_{CORE}")
			(pintype "power_in")
		)
		(pad "3" smd roundrect
			(at -3.938 -2.25 180)
			(size 0.875 0.3)
			(layers "F.Cu" "F.Mask" "F.Paste")
			(roundrect_rratio 0.25)
			(net 710 "/USB PHY/FTDI_XI")
			(pinfunction "OSCI")
			(pintype "input")
		)
		(pad "4" smd roundrect
			(at -3.938 -1.75 180)
			(size 0.875 0.3)
			(layers "F.Cu" "F.Mask" "F.Paste")
			(roundrect_rratio 0.25)
			(net 713 "/USB PHY/FTDI_XO")
			(pinfunction "OSCO")
			(pintype "output")
		)
		(pad "5" smd roundrect
			(at -3.938 -1.25 180)
			(size 0.875 0.3)
			(layers "F.Cu" "F.Mask" "F.Paste")
			(roundrect_rratio 0.25)
			(net 714 "/USB PHY/FTDI_VPHY")
			(pinfunction "V_{PHY}")
			(pintype "power_in")
		)
		(pad "6" smd roundrect
			(at -3.938 -0.75 180)
			(size 0.875 0.3)
			(layers "F.Cu" "F.Mask" "F.Paste")
			(roundrect_rratio 0.25)
			(net 920 "/USB PHY/FTDI_REF")
			(pinfunction "REF")
			(pintype "input")
		)
		(pad "7" smd roundrect
			(at -3.938 -0.25 180)
			(size 0.875 0.3)
			(layers "F.Cu" "F.Mask" "F.Paste")
			(roundrect_rratio 0.25)
			(net 839 "/USB PHY/USB_DBG_CONN_D-")
			(pinfunction "D-")
			(pintype "bidirectional")
		)
		(pad "8" smd roundrect
			(at -3.938 0.249 180)
			(size 0.875 0.3)
			(layers "F.Cu" "F.Mask" "F.Paste")
			(roundrect_rratio 0.25)
			(net 838 "/USB PHY/USB_DBG_CONN_D+")
			(pinfunction "D+")
			(pintype "bidirectional")
		)
		(pad "9" smd roundrect
			(at -3.938 0.749 180)
			(size 0.875 0.3)
			(layers "F.Cu" "F.Mask" "F.Paste")
			(roundrect_rratio 0.25)
			(net 711 "/USB PHY/FTDI_VPLL")
			(pinfunction "V_{PLL}")
			(pintype "power_in")
		)
		(pad "10" smd roundrect
			(at -3.938 1.249 180)
			(size 0.875 0.3)
			(layers "F.Cu" "F.Mask" "F.Paste")
			(roundrect_rratio 0.25)
			(net 1 "GND")
			(pinfunction "TEST")
			(pintype "input")
		)
		(pad "11" smd roundrect
			(at -3.938 1.749 180)
			(size 0.875 0.3)
			(layers "F.Cu" "F.Mask" "F.Paste")
			(roundrect_rratio 0.25)
			(net 919 "/USB PHY/FTDI_RST")
			(pinfunction "~{RESET}")
			(pintype "input")
		)
		(pad "12" smd roundrect
			(at -3.938 2.249 180)
			(size 0.875 0.3)
			(layers "F.Cu" "F.Mask" "F.Paste")
			(roundrect_rratio 0.25)
			(net 1015 "/USB PHY/FTDI_JTAG_TCK")
			(pinfunction "ADBUS0")
			(pintype "bidirectional")
		)
		(pad "13" smd roundrect
			(at -3.938 2.749 180)
			(size 0.875 0.3)
			(layers "F.Cu" "F.Mask" "F.Paste")
			(roundrect_rratio 0.25)
			(net 1016 "/USB PHY/FTDI_JTAG_TDI")
			(pinfunction "ADBUS1")
			(pintype "bidirectional")
		)
		(pad "14" smd roundrect
			(at -3.938 3.249 180)
			(size 0.875 0.3)
			(layers "F.Cu" "F.Mask" "F.Paste")
			(roundrect_rratio 0.25)
			(net 1017 "/USB PHY/FTDI_JTAG_TDO")
			(pinfunction "ADBUS2")
			(pintype "bidirectional")
		)
		(pad "15" smd roundrect
			(at -3.25 3.937 270)
			(size 0.875 0.3)
			(layers "F.Cu" "F.Mask" "F.Paste")
			(roundrect_rratio 0.25)
			(net 1018 "/USB PHY/FTDI_JTAG_TMS")
			(pinfunction "ADBUS3")
			(pintype "bidirectional")
		)
		(pad "16" smd roundrect
			(at -2.75 3.937 270)
			(size 0.875 0.3)
			(layers "F.Cu" "F.Mask" "F.Paste")
			(roundrect_rratio 0.25)
			(net 707 "/USB PHY/FTDI_3V3")
			(pinfunction "V_{CCIO}")
			(pintype "power_in")
		)
		(pad "17" smd roundrect
			(at -2.25 3.937 270)
			(size 0.875 0.3)
			(layers "F.Cu" "F.Mask" "F.Paste")
			(roundrect_rratio 0.25)
			(net 1182 "unconnected-(U20-ADBUS4-Pad17)")
			(pinfunction "ADBUS4")
			(pintype "bidirectional+no_connect")
		)
		(pad "18" smd roundrect
			(at -1.75 3.937 270)
			(size 0.875 0.3)
			(layers "F.Cu" "F.Mask" "F.Paste")
			(roundrect_rratio 0.25)
			(net 1020 "/USB PHY/FTDI_JTAG_RST")
			(pinfunction "ADBUS5")
			(pintype "bidirectional")
		)
		(pad "19" smd roundrect
			(at -1.25 3.937 270)
			(size 0.875 0.3)
			(layers "F.Cu" "F.Mask" "F.Paste")
			(roundrect_rratio 0.25)
			(net 1183 "unconnected-(U20-ADBUS6-Pad19)")
			(pinfunction "ADBUS6")
			(pintype "bidirectional+no_connect")
		)
		(pad "20" smd roundrect
			(at -0.75 3.937 270)
			(size 0.875 0.3)
			(layers "F.Cu" "F.Mask" "F.Paste")
			(roundrect_rratio 0.25)
			(net 1184 "unconnected-(U20-ADBUS7-Pad20)")
			(pinfunction "ADBUS7")
			(pintype "bidirectional+no_connect")
		)
		(pad "21" smd roundrect
			(at -0.25 3.937 270)
			(size 0.875 0.3)
			(layers "F.Cu" "F.Mask" "F.Paste")
			(roundrect_rratio 0.25)
			(net 1 "GND")
			(pinfunction "GND")
			(pintype "power_in")
		)
		(pad "22" smd roundrect
			(at 0.249 3.937 270)
			(size 0.875 0.3)
			(layers "F.Cu" "F.Mask" "F.Paste")
			(roundrect_rratio 0.25)
			(net 1023 "/USB PHY/BDBUS0")
			(pinfunction "BDBUS0")
			(pintype "bidirectional")
		)
		(pad "23" smd roundrect
			(at 0.749 3.937 270)
			(size 0.875 0.3)
			(layers "F.Cu" "F.Mask" "F.Paste")
			(roundrect_rratio 0.25)
			(net 1024 "/USB PHY/BDBUS1")
			(pinfunction "BDBUS1")
			(pintype "bidirectional")
		)
		(pad "24" smd roundrect
			(at 1.249 3.937 270)
			(size 0.875 0.3)
			(layers "F.Cu" "F.Mask" "F.Paste")
			(roundrect_rratio 0.25)
			(net 1025 "/USB PHY/BDBUS2")
			(pinfunction "BDBUS2")
			(pintype "bidirectional")
		)
		(pad "25" smd roundrect
			(at 1.749 3.937 270)
			(size 0.875 0.3)
			(layers "F.Cu" "F.Mask" "F.Paste")
			(roundrect_rratio 0.25)
			(net 925 "/USB PHY/BDBUS3")
			(pinfunction "BDBUS3")
			(pintype "bidirectional")
		)
		(pad "26" smd roundrect
			(at 2.249 3.937 270)
			(size 0.875 0.3)
			(layers "F.Cu" "F.Mask" "F.Paste")
			(roundrect_rratio 0.25)
			(net 934 "/USB PHY/SPI_EN")
			(pinfunction "BDBUS4")
			(pintype "bidirectional")
		)
		(pad "27" smd roundrect
			(at 2.749 3.937 270)
			(size 0.875 0.3)
			(layers "F.Cu" "F.Mask" "F.Paste")
			(roundrect_rratio 0.25)
			(net 940 "/USB PHY/I2C_EN")
			(pinfunction "BDBUS5")
			(pintype "bidirectional")
		)
		(pad "28" smd roundrect
			(at 3.249 3.937 270)
			(size 0.875 0.3)
			(layers "F.Cu" "F.Mask" "F.Paste")
			(roundrect_rratio 0.25)
			(net 1185 "unconnected-(U20-BDBUS6-Pad28)")
			(pinfunction "BDBUS6")
			(pintype "bidirectional+no_connect")
		)
		(pad "29" smd roundrect
			(at 3.937 3.249 180)
			(size 0.875 0.3)
			(layers "F.Cu" "F.Mask" "F.Paste")
			(roundrect_rratio 0.25)
			(net 1186 "unconnected-(U20-BDBUS7-Pad29)")
			(pinfunction "BDBUS7")
			(pintype "bidirectional+no_connect")
		)
		(pad "30" smd roundrect
			(at 3.937 2.749 180)
			(size 0.875 0.3)
			(layers "F.Cu" "F.Mask" "F.Paste")
			(roundrect_rratio 0.25)
			(net 1187 "unconnected-(U20-~{SUSPEND}-Pad30)")
			(pinfunction "~{SUSPEND}")
			(pintype "output+no_connect")
		)
		(pad "31" smd roundrect
			(at 3.937 2.249 180)
			(size 0.875 0.3)
			(layers "F.Cu" "F.Mask" "F.Paste")
			(roundrect_rratio 0.25)
			(net 712 "/USB PHY/FTDI_VCORE")
			(pinfunction "V_{CORE}")
			(pintype "passive")
		)
		(pad "32" smd roundrect
			(at 3.937 1.749 180)
			(size 0.875 0.3)
			(layers "F.Cu" "F.Mask" "F.Paste")
			(roundrect_rratio 0.25)
			(net 921 "/USB PHY/FTDI_UART0_TX")
			(pinfunction "CDBUS0")
			(pintype "bidirectional")
		)
		(pad "33" smd roundrect
			(at 3.937 1.249 180)
			(size 0.875 0.3)
			(layers "F.Cu" "F.Mask" "F.Paste")
			(roundrect_rratio 0.25)
			(net 922 "/USB PHY/FTDI_UART0_RX")
			(pinfunction "CDBUS1")
			(pintype "bidirectional")
		)
		(pad "34" smd roundrect
			(at 3.937 0.749 180)
			(size 0.875 0.3)
			(layers "F.Cu" "F.Mask" "F.Paste")
			(roundrect_rratio 0.25)
			(net 1188 "unconnected-(U20-CDBUS2-Pad34)")
			(pinfunction "CDBUS2")
			(pintype "bidirectional+no_connect")
		)
		(pad "35" smd roundrect
			(at 3.937 0.249 180)
			(size 0.875 0.3)
			(layers "F.Cu" "F.Mask" "F.Paste")
			(roundrect_rratio 0.25)
			(net 1189 "unconnected-(U20-CDBUS3-Pad35)")
			(pinfunction "CDBUS3")
			(pintype "bidirectional+no_connect")
		)
		(pad "36" smd roundrect
			(at 3.937 -0.25 180)
			(size 0.875 0.3)
			(layers "F.Cu" "F.Mask" "F.Paste")
			(roundrect_rratio 0.25)
			(net 707 "/USB PHY/FTDI_3V3")
			(pinfunction "V_{CCIO}")
			(pintype "passive")
		)
		(pad "37" smd roundrect
			(at 3.937 -0.75 180)
			(size 0.875 0.3)
			(layers "F.Cu" "F.Mask" "F.Paste")
			(roundrect_rratio 0.25)
			(net 1190 "unconnected-(U20-CDBUS4-Pad37)")
			(pinfunction "CDBUS4")
			(pintype "bidirectional+no_connect")
		)
		(pad "38" smd roundrect
			(at 3.937 -1.25 180)
			(size 0.875 0.3)
			(layers "F.Cu" "F.Mask" "F.Paste")
			(roundrect_rratio 0.25)
			(net 1196 "unconnected-(U20-CDBUS5-Pad38)")
			(pinfunction "CDBUS5")
			(pintype "bidirectional+no_connect")
		)
		(pad "39" smd roundrect
			(at 3.937 -1.75 180)
			(size 0.875 0.3)
			(layers "F.Cu" "F.Mask" "F.Paste")
			(roundrect_rratio 0.25)
			(net 1197 "unconnected-(U20-CDBUS6-Pad39)")
			(pinfunction "CDBUS6")
			(pintype "bidirectional+no_connect")
		)
		(pad "40" smd roundrect
			(at 3.937 -2.25 180)
			(size 0.875 0.3)
			(layers "F.Cu" "F.Mask" "F.Paste")
			(roundrect_rratio 0.25)
			(net 1198 "unconnected-(U20-CDBUS7-Pad40)")
			(pinfunction "CDBUS7")
			(pintype "bidirectional+no_connect")
		)
		(pad "41" smd roundrect
			(at 3.937 -2.75 180)
			(size 0.875 0.3)
			(layers "F.Cu" "F.Mask" "F.Paste")
			(roundrect_rratio 0.25)
			(net 1 "GND")
			(pinfunction "GND")
			(pintype "passive")
		)
		(pad "42" smd roundrect
			(at 3.937 -3.25 180)
			(size 0.875 0.3)
			(layers "F.Cu" "F.Mask" "F.Paste")
			(roundrect_rratio 0.25)
			(net 923 "/USB PHY/FTDI_UART1_TX")
			(pinfunction "DDBUS0")
			(pintype "bidirectional")
		)
		(pad "43" smd roundrect
			(at 3.249 -3.938 270)
			(size 0.875 0.3)
			(layers "F.Cu" "F.Mask" "F.Paste")
			(roundrect_rratio 0.25)
			(net 712 "/USB PHY/FTDI_VCORE")
			(pinfunction "V_{REGOUT}")
			(pintype "power_out")
		)
		(pad "44" smd roundrect
			(at 2.749 -3.938 270)
			(size 0.875 0.3)
			(layers "F.Cu" "F.Mask" "F.Paste")
			(roundrect_rratio 0.25)
			(net 707 "/USB PHY/FTDI_3V3")
			(pinfunction "V_{REGIN}")
			(pintype "power_in")
		)
		(pad "45" smd roundrect
			(at 2.249 -3.938 270)
			(size 0.875 0.3)
			(layers "F.Cu" "F.Mask" "F.Paste")
			(roundrect_rratio 0.25)
			(net 1 "GND")
			(pinfunction "GND")
			(pintype "passive")
		)
		(pad "46" smd roundrect
			(at 1.749 -3.938 270)
			(size 0.875 0.3)
			(layers "F.Cu" "F.Mask" "F.Paste")
			(roundrect_rratio 0.25)
			(net 924 "/USB PHY/FTDI_UART1_RX")
			(pinfunction "DDBUS1")
			(pintype "bidirectional")
		)
		(pad "47" smd roundrect
			(at 1.249 -3.938 270)
			(size 0.875 0.3)
			(layers "F.Cu" "F.Mask" "F.Paste")
			(roundrect_rratio 0.25)
			(net 1199 "unconnected-(U20-DDBUS2-Pad47)")
			(pinfunction "DDBUS2")
			(pintype "bidirectional+no_connect")
		)
		(pad "48" smd roundrect
			(at 0.749 -3.938 270)
			(size 0.875 0.3)
			(layers "F.Cu" "F.Mask" "F.Paste")
			(roundrect_rratio 0.25)
			(net 1200 "unconnected-(U20-DDBUS3-Pad48)")
			(pinfunction "DDBUS3")
			(pintype "bidirectional+no_connect")
		)
		(pad "49" smd roundrect
			(at 0.249 -3.938 270)
			(size 0.875 0.3)
			(layers "F.Cu" "F.Mask" "F.Paste")
			(roundrect_rratio 0.25)
			(net 1201 "unconnected-(U20-DDBUS4-Pad49)")
			(pinfunction "DDBUS4")
			(pintype "bidirectional+no_connect")
		)
		(pad "50" smd roundrect
			(at -0.25 -3.938 270)
			(size 0.875 0.3)
			(layers "F.Cu" "F.Mask" "F.Paste")
			(roundrect_rratio 0.25)
			(net 707 "/USB PHY/FTDI_3V3")
			(pinfunction "V_{CCIO}")
			(pintype "passive")
		)
		(pad "51" smd roundrect
			(at -0.75 -3.938 270)
			(size 0.875 0.3)
			(layers "F.Cu" "F.Mask" "F.Paste")
			(roundrect_rratio 0.25)
			(net 1202 "unconnected-(U20-DDBUS5-Pad51)")
			(pinfunction "DDBUS5")
			(pintype "bidirectional+no_connect")
		)
		(pad "52" smd roundrect
			(at -1.25 -3.938 270)
			(size 0.875 0.3)
			(layers "F.Cu" "F.Mask" "F.Paste")
			(roundrect_rratio 0.25)
			(net 1203 "unconnected-(U20-DDBUS6-Pad52)")
			(pinfunction "DDBUS6")
			(pintype "bidirectional+no_connect")
		)
		(pad "53" smd roundrect
			(at -1.75 -3.938 270)
			(size 0.875 0.3)
			(layers "F.Cu" "F.Mask" "F.Paste")
			(roundrect_rratio 0.25)
			(net 1204 "unconnected-(U20-DDBUS7-Pad53)")
			(pinfunction "DDBUS7")
			(pintype "bidirectional+no_connect")
		)
		(pad "54" smd roundrect
			(at -2.25 -3.938 270)
			(size 0.875 0.3)
			(layers "F.Cu" "F.Mask" "F.Paste")
			(roundrect_rratio 0.25)
			(net 918 "/USB PHY/FTDI_PWREN")
			(pinfunction "~{PWR_{EN}}")
			(pintype "output")
		)
		(pad "55" smd roundrect
			(at -2.75 -3.938 270)
			(size 0.875 0.3)
			(layers "F.Cu" "F.Mask" "F.Paste")
			(roundrect_rratio 0.25)
			(net 998 "/USB PHY/FTDI_EEDAT")
			(pinfunction "EEDATA")
			(pintype "bidirectional")
		)
		(pad "56" smd roundrect
			(at -3.25 -3.938 270)
			(size 0.875 0.3)
			(layers "F.Cu" "F.Mask" "F.Paste")
			(roundrect_rratio 0.25)
			(net 996 "/USB PHY/FTDI_EECLK")
			(pinfunction "EECLK")
			(pintype "output")
		)
		(pad "57" smd rect
			(at 0 0 180)
			(size 5.9 5.9)
			(layers "F.Cu" "F.Mask")
			(net 1 "GND")
			(pinfunction "GND")
			(pintype "passive")
		)
	)
)
